(kicad_pcb
	(version 20241229)
	(generator "pcbnew")
	(generator_version "9.0")
	(general
		(thickness 1.6642)
		(legacy_teardrops no)
	)
	(paper "A3")
	(title_block
		(title "PolarFire SoM")
		(date "2025-07-22")
		(rev "1.1.4")
		(company "Antmicro Ltd")
		(comment 1 "www.antmicro.com")
		(comment 9 "footprints 280-283 of 470")
	)
	(layers
		(0 "F.Cu" mixed)
		(4 "In1.Cu" power)
		(6 "In2.Cu" signal)
		(8 "In3.Cu" power)
		(10 "In4.Cu" signal)
		(12 "In5.Cu" power)
		(14 "In6.Cu" power)
		(16 "In7.Cu" signal)
		(18 "In8.Cu" power)
		(20 "In9.Cu" signal)
		(22 "In10.Cu" power)
		(24 "In11.Cu" signal)
		(26 "In12.Cu" signal)
		(2 "B.Cu" mixed)
		(9 "F.Adhes" user "F.Adhesive")
		(11 "B.Adhes" user "B.Adhesive")
		(13 "F.Paste" user)
		(15 "B.Paste" user)
		(5 "F.SilkS" user "F.Silkscreen")
		(7 "B.SilkS" user "B.Silkscreen")
		(1 "F.Mask" user)
		(3 "B.Mask" user)
		(17 "Dwgs.User" user "User.Drawings")
		(19 "Cmts.User" user "User.Comments")
		(21 "Eco1.User" user "User.Eco1")
		(23 "Eco2.User" user "User.Eco2")
		(25 "Edge.Cuts" user)
		(27 "Margin" user)
		(31 "F.CrtYd" user "F.Courtyard")
		(29 "B.CrtYd" user "B.Courtyard")
		(35 "F.Fab" user)
		(33 "B.Fab" user)
	)
	(footprint "antmicro-footprints:C_0402_1005Metric"
		(layer "B.Cu")
		(at 216.329 117.56 90)
		(descr "Capacitor SMD 0402")
		(tags "capacitor SMD 0402")
		(property "Reference" "C117"
			(at -3.715 0.471 90)
			(layer "B.SilkS")
			(effects
				(font
					(size 0.7 0.7)
					(thickness 0.15)
				)
				(justify right bottom mirror)
			)
		)
		(property "Value" "C_100n_0402"
			(at -1.022927 -2.155213 90)
			(layer "B.Fab")
			(hide yes)
			(effects
				(font
					(size 0.7 0.7)
					(thickness 0.15)
				)
				(justify right bottom mirror)
			)
		)
		(property "Datasheet" "https://www.murata.com/products/productdetail?partno=GRM155R61H104KE14%23"
			(at 0 0 90)
			(layer "F.Fab")
			(hide yes)
			(effects
				(font
					(size 1.27 1.27)
					(thickness 0.15)
				)
			)
		)
		(property "Description" "SMD Multilayer Ceramic Capacitor, 0.1 µF, 50 V, 0402 [1005 Metric], ± 10%, X5R, GRM Series"
			(at 0 0 90)
			(layer "F.Fab")
			(hide yes)
			(effects
				(font
					(size 1.27 1.27)
					(thickness 0.15)
				)
			)
		)
		(property "Author" "Antmicro"
			(at 333.889 -98.769 0)
			(layer "B.Fab")
			(hide yes)
			(effects
				(font
					(size 1 1)
					(thickness 0.15)
				)
				(justify mirror)
			)
		)
		(property "Dielectric" "X5R"
			(at 333.889 -98.769 0)
			(layer "B.Fab")
			(hide yes)
			(effects
				(font
					(size 1 1)
					(thickness 0.15)
				)
				(justify mirror)
			)
		)
		(property "License" "Apache-2.0"
			(at 333.889 -98.769 0)
			(layer "B.Fab")
			(hide yes)
			(effects
				(font
					(size 1 1)
					(thickness 0.15)
				)
				(justify mirror)
			)
		)
		(property "MPN" "GRM155R61H104KE14D"
			(at 333.889 -98.769 0)
			(layer "B.Fab")
			(hide yes)
			(effects
				(font
					(size 1 1)
					(thickness 0.15)
				)
				(justify mirror)
			)
		)
		(property "Manufacturer" "Murata"
			(at 333.889 -98.769 0)
			(layer "B.Fab")
			(hide yes)
			(effects
				(font
					(size 1 1)
					(thickness 0.15)
				)
				(justify mirror)
			)
		)
		(property "Public" ""
			(at 333.889 -98.769 0)
			(layer "B.Fab")
			(hide yes)
			(effects
				(font
					(size 1 1)
					(thickness 0.15)
				)
				(justify mirror)
			)
		)
		(property "Val" "100n"
			(at 333.889 -98.769 0)
			(layer "B.Fab")
			(hide yes)
			(effects
				(font
					(size 1 1)
					(thickness 0.15)
				)
				(justify mirror)
			)
		)
		(property "Voltage" "50V"
			(at 333.889 -98.769 0)
			(layer "B.Fab")
			(hide yes)
			(effects
				(font
					(size 1 1)
					(thickness 0.15)
				)
				(justify mirror)
			)
		)
		(sheetname "/Ethernet/")
		(sheetfile "ethernet.kicad_sch")
		(attr smd)
		(fp_rect
			(start -0.925 0.47)
			(end 0.925 -0.47)
			(stroke
				(width 0.05)
				(type default)
			)
			(fill no)
			(layer "B.CrtYd")
		)
		(fp_line
			(start 0.504 -0.248)
			(end -0.494 -0.248)
			(stroke
				(width 0.15)
				(type solid)
			)
			(layer "B.Fab")
		)
		(fp_line
			(start -0.494 -0.248)
			(end -0.494 0.25)
			(stroke
				(width 0.15)
				(type solid)
			)
			(layer "B.Fab")
		)
		(fp_line
			(start 0.504 0.25)
			(end 0.504 -0.248)
			(stroke
				(width 0.15)
				(type solid)
			)
			(layer "B.Fab")
		)
		(fp_line
			(start -0.494 0.25)
			(end 0.504 0.25)
			(stroke
				(width 0.15)
				(type solid)
			)
			(layer "B.Fab")
		)
		(fp_text user "License: Apache-2.0"
			(at -0.939 -5.799 270)
			(layer "B.Fab")
			(effects
				(font
					(size 0.7 0.7)
					(thickness 0.15)
				)
				(justify left bottom mirror)
			)
		)
		(fp_text user "Author: Antmicro"
			(at -0.939 -3.399 270)
			(layer "B.Fab")
			(effects
				(font
					(size 0.7 0.7)
					(thickness 0.15)
				)
				(justify left bottom mirror)
			)
		)
		(fp_text user "${REFERENCE}"
			(at -0.939 -4.599 270)
			(layer "B.Fab")
			(effects
				(font
					(size 0.7 0.7)
					(thickness 0.15)
				)
				(justify left bottom mirror)
			)
		)
		(pad "1" smd roundrect
			(at -0.48 0 90)
			(size 0.59 0.64)
			(layers "B.Cu" "B.Mask" "B.Paste")
			(roundrect_rratio 0.25)
			(net 417 "GND")
			(pintype "passive")
		)
		(pad "2" smd roundrect
			(at 0.48 0 90)
			(size 0.59 0.64)
			(layers "B.Cu" "B.Mask" "B.Paste")
			(roundrect_rratio 0.25)
			(net 50 "+3V3")
			(pintype "passive")
		)
	)
	(footprint "antmicro-footprints:C_0402_1005Metric"
		(layer "B.Cu")
		(at 208.2 139.15)
		(descr "Capacitor SMD 0402")
		(tags "capacitor SMD 0402")
		(property "Reference" "C130"
			(at -1.47 1.7 0)
			(layer "B.SilkS")
			(effects
				(font
					(size 0.7 0.7)
					(thickness 0.15)
				)
				(justify right bottom mirror)
			)
		)
		(property "Value" "C_100n_0402"
			(at -1.022927 -2.155213 0)
			(layer "B.Fab")
			(hide yes)
			(effects
				(font
					(size 0.7 0.7)
					(thickness 0.15)
				)
				(justify right bottom mirror)
			)
		)
		(property "Datasheet" "https://www.murata.com/products/productdetail?partno=GRM155R61H104KE14%23"
			(at 0 0 0)
			(layer "F.Fab")
			(hide yes)
			(effects
				(font
					(size 1.27 1.27)
					(thickness 0.15)
				)
			)
		)
		(property "Description" "SMD Multilayer Ceramic Capacitor, 0.1 µF, 50 V, 0402 [1005 Metric], ± 10%, X5R, GRM Series"
			(at 0 0 0)
			(layer "F.Fab")
			(hide yes)
			(effects
				(font
					(size 1.27 1.27)
					(thickness 0.15)
				)
			)
		)
		(property "Author" "Antmicro"
			(at 0 0 0)
			(layer "B.Fab")
			(hide yes)
			(effects
				(font
					(size 1 1)
					(thickness 0.15)
				)
				(justify mirror)
			)
		)
		(property "Dielectric" "X5R"
			(at 0 0 0)
			(layer "B.Fab")
			(hide yes)
			(effects
				(font
					(size 1 1)
					(thickness 0.15)
				)
				(justify mirror)
			)
		)
		(property "License" "Apache-2.0"
			(at 0 0 0)
			(layer "B.Fab")
			(hide yes)
			(effects
				(font
					(size 1 1)
					(thickness 0.15)
				)
				(justify mirror)
			)
		)
		(property "MPN" "GRM155R61H104KE14D"
			(at 0 0 0)
			(layer "B.Fab")
			(hide yes)
			(effects
				(font
					(size 1 1)
					(thickness 0.15)
				)
				(justify mirror)
			)
		)
		(property "Manufacturer" "Murata"
			(at 0 0 0)
			(layer "B.Fab")
			(hide yes)
			(effects
				(font
					(size 1 1)
					(thickness 0.15)
				)
				(justify mirror)
			)
		)
		(property "Public" ""
			(at 0 0 0)
			(layer "B.Fab")
			(hide yes)
			(effects
				(font
					(size 1 1)
					(thickness 0.15)
				)
				(justify mirror)
			)
		)
		(property "Val" "100n"
			(at 0 0 0)
			(layer "B.Fab")
			(hide yes)
			(effects
				(font
					(size 1 1)
					(thickness 0.15)
				)
				(justify mirror)
			)
		)
		(property "Voltage" "50V"
			(at 0 0 0)
			(layer "B.Fab")
			(hide yes)
			(effects
				(font
					(size 1 1)
					(thickness 0.15)
				)
				(justify mirror)
			)
		)
		(sheetname "/FPGA GPIO/")
		(sheetfile "fpga-gpio.kicad_sch")
		(attr smd)
		(fp_rect
			(start -0.925 0.47)
			(end 0.925 -0.47)
			(stroke
				(width 0.05)
				(type default)
			)
			(fill no)
			(layer "B.CrtYd")
		)
		(fp_line
			(start -0.494 -0.248)
			(end -0.494 0.25)
			(stroke
				(width 0.15)
				(type solid)
			)
			(layer "B.Fab")
		)
		(fp_line
			(start -0.494 0.25)
			(end 0.504 0.25)
			(stroke
				(width 0.15)
				(type solid)
			)
			(layer "B.Fab")
		)
		(fp_line
			(start 0.504 -0.248)
			(end -0.494 -0.248)
			(stroke
				(width 0.15)
				(type solid)
			)
			(layer "B.Fab")
		)
		(fp_line
			(start 0.504 0.25)
			(end 0.504 -0.248)
			(stroke
				(width 0.15)
				(type solid)
			)
			(layer "B.Fab")
		)
		(fp_text user "Author: Antmicro"
			(at -0.939 -3.399 180)
			(layer "B.Fab")
			(effects
				(font
					(size 0.7 0.7)
					(thickness 0.15)
				)
				(justify left bottom mirror)
			)
		)
		(fp_text user "${REFERENCE}"
			(at -0.939 -4.599 180)
			(layer "B.Fab")
			(effects
				(font
					(size 0.7 0.7)
					(thickness 0.15)
				)
				(justify left bottom mirror)
			)
		)
		(fp_text user "License: Apache-2.0"
			(at -0.939 -5.799 180)
			(layer "B.Fab")
			(effects
				(font
					(size 0.7 0.7)
					(thickness 0.15)
				)
				(justify left bottom mirror)
			)
		)
		(pad "1" smd roundrect
			(at -0.48 0)
			(size 0.59 0.64)
			(layers "B.Cu" "B.Mask" "B.Paste")
			(roundrect_rratio 0.25)
			(net 649 "VDD")
			(pintype "passive")
		)
		(pad "2" smd roundrect
			(at 0.48 0)
			(size 0.59 0.64)
			(layers "B.Cu" "B.Mask" "B.Paste")
			(roundrect_rratio 0.25)
			(net 417 "GND")
			(pintype "passive")
		)
	)
	(footprint "antmicro-footprints:C_0402_1005Metric"
		(layer "B.Cu")
		(at 210.577 123.3972)
		(descr "Capacitor SMD 0402")
		(tags "capacitor SMD 0402")
		(property "Reference" "C259"
			(at -3.702 2.6528 0)
			(layer "B.SilkS")
			(effects
				(font
					(size 0.7 0.7)
					(thickness 0.15)
				)
				(justify right bottom mirror)
			)
		)
		(property "Value" "C_100n_0402"
			(at -1.022927 -2.155213 0)
			(layer "B.Fab")
			(hide yes)
			(effects
				(font
					(size 0.7 0.7)
					(thickness 0.15)
				)
				(justify right bottom mirror)
			)
		)
		(property "Datasheet" "https://www.murata.com/products/productdetail?partno=GRM155R61H104KE14%23"
			(at 0 0 0)
			(layer "F.Fab")
			(hide yes)
			(effects
				(font
					(size 1.27 1.27)
					(thickness 0.15)
				)
			)
		)
		(property "Description" "SMD Multilayer Ceramic Capacitor, 0.1 µF, 50 V, 0402 [1005 Metric], ± 10%, X5R, GRM Series"
			(at 0 0 0)
			(layer "F.Fab")
			(hide yes)
			(effects
				(font
					(size 1.27 1.27)
					(thickness 0.15)
				)
			)
		)
		(property "Author" "Antmicro"
			(at 0 0 0)
			(layer "B.Fab")
			(hide yes)
			(effects
				(font
					(size 1 1)
					(thickness 0.15)
				)
				(justify mirror)
			)
		)
		(property "Dielectric" "X5R"
			(at 0 0 0)
			(layer "B.Fab")
			(hide yes)
			(effects
				(font
					(size 1 1)
					(thickness 0.15)
				)
				(justify mirror)
			)
		)
		(property "License" "Apache-2.0"
			(at 0 0 0)
			(layer "B.Fab")
			(hide yes)
			(effects
				(font
					(size 1 1)
					(thickness 0.15)
				)
				(justify mirror)
			)
		)
		(property "MPN" "GRM155R61H104KE14D"
			(at 0 0 0)
			(layer "B.Fab")
			(hide yes)
			(effects
				(font
					(size 1 1)
					(thickness 0.15)
				)
				(justify mirror)
			)
		)
		(property "Manufacturer" "Murata"
			(at 0 0 0)
			(layer "B.Fab")
			(hide yes)
			(effects
				(font
					(size 1 1)
					(thickness 0.15)
				)
				(justify mirror)
			)
		)
		(property "Public" ""
			(at 0 0 0)
			(layer "B.Fab")
			(hide yes)
			(effects
				(font
					(size 1 1)
					(thickness 0.15)
				)
				(justify mirror)
			)
		)
		(property "Val" "100n"
			(at 0 0 0)
			(layer "B.Fab")
			(hide yes)
			(effects
				(font
					(size 1 1)
					(thickness 0.15)
				)
				(justify mirror)
			)
		)
		(property "Voltage" "50V"
			(at 0 0 0)
			(layer "B.Fab")
			(hide yes)
			(effects
				(font
					(size 1 1)
					(thickness 0.15)
				)
				(justify mirror)
			)
		)
		(sheetname "/Ethernet/")
		(sheetfile "ethernet.kicad_sch")
		(attr smd)
		(fp_rect
			(start -0.925 0.47)
			(end 0.925 -0.47)
			(stroke
				(width 0.05)
				(type default)
			)
			(fill no)
			(layer "B.CrtYd")
		)
		(fp_line
			(start -0.494 -0.248)
			(end -0.494 0.25)
			(stroke
				(width 0.15)
				(type solid)
			)
			(layer "B.Fab")
		)
		(fp_line
			(start -0.494 0.25)
			(end 0.504 0.25)
			(stroke
				(width 0.15)
				(type solid)
			)
			(layer "B.Fab")
		)
		(fp_line
			(start 0.504 -0.248)
			(end -0.494 -0.248)
			(stroke
				(width 0.15)
				(type solid)
			)
			(layer "B.Fab")
		)
		(fp_line
			(start 0.504 0.25)
			(end 0.504 -0.248)
			(stroke
				(width 0.15)
				(type solid)
			)
			(layer "B.Fab")
		)
		(fp_text user "${REFERENCE}"
			(at -0.939 -4.599 180)
			(layer "B.Fab")
			(effects
				(font
					(size 0.7 0.7)
					(thickness 0.15)
				)
				(justify left bottom mirror)
			)
		)
		(fp_text user "Author: Antmicro"
			(at -0.939 -3.399 180)
			(layer "B.Fab")
			(effects
				(font
					(size 0.7 0.7)
					(thickness 0.15)
				)
				(justify left bottom mirror)
			)
		)
		(fp_text user "License: Apache-2.0"
			(at -0.939 -5.799 180)
			(layer "B.Fab")
			(effects
				(font
					(size 0.7 0.7)
					(thickness 0.15)
				)
				(justify left bottom mirror)
			)
		)
		(pad "1" smd roundrect
			(at -0.48 0)
			(size 0.59 0.64)
			(layers "B.Cu" "B.Mask" "B.Paste")
			(roundrect_rratio 0.25)
			(net 42 "/Ethernet/SGMII.RX0_P")
			(pintype "passive")
		)
		(pad "2" smd roundrect
			(at 0.48 0)
			(size 0.59 0.64)
			(layers "B.Cu" "B.Mask" "B.Paste")
			(roundrect_rratio 0.25)
			(net 170 "/Ethernet/SGMII_SO_P")
			(pintype "passive")
		)
	)
	(footprint "antmicro-footprints:C_0402_1005Metric"
		(layer "B.Cu")
		(at 189.28 143.18 180)
		(descr "Capacitor SMD 0402")
		(tags "capacitor SMD 0402")
		(property "Reference" "C64"
			(at -1.195 0.53 0)
			(layer "B.SilkS")
			(effects
				(font
					(size 0.7 0.7)
					(thickness 0.15)
				)
				(justify left bottom mirror)
			)
		)
		(property "Value" "C_10n_0402"
			(at -1.022927 -2.155213 0)
			(layer "B.Fab")
			(hide yes)
			(effects
				(font
					(size 0.7 0.7)
					(thickness 0.15)
				)
				(justify left bottom mirror)
			)
		)
		(property "Datasheet" "https://www.murata.com/products/productdetail?partno=GRM155R71H103KA88%23"
			(at 0 0 180)
			(layer "F.Fab")
			(hide yes)
			(effects
				(font
					(size 1.27 1.27)
					(thickness 0.15)
				)
			)
		)
		(property "Description" "SMD Multilayer Ceramic Capacitor, 10000 pF, 50 V, 0402 [1005 Metric], ± 10%, X7R, GRM Series"
			(at 0 0 180)
			(layer "F.Fab")
			(hide yes)
			(effects
				(font
					(size 1.27 1.27)
					(thickness 0.15)
				)
			)
		)
		(property "Author" "Antmicro"
			(at 378.56 286.36 0)
			(layer "B.Fab")
			(hide yes)
			(effects
				(font
					(size 1 1)
					(thickness 0.15)
				)
				(justify mirror)
			)
		)
		(property "Dielectric" "X7R"
			(at 378.56 286.36 0)
			(layer "B.Fab")
			(hide yes)
			(effects
				(font
					(size 1 1)
					(thickness 0.15)
				)
				(justify mirror)
			)
		)
		(property "License" "Apache-2.0"
			(at 378.56 286.36 0)
			(layer "B.Fab")
			(hide yes)
			(effects
				(font
					(size 1 1)
					(thickness 0.15)
				)
				(justify mirror)
			)
		)
		(property "MPN" "GRM155R71H103KA88D"
			(at 378.56 286.36 0)
			(layer "B.Fab")
			(hide yes)
			(effects
				(font
					(size 1 1)
					(thickness 0.15)
				)
				(justify mirror)
			)
		)
		(property "Manufacturer" "Murata"
			(at 378.56 286.36 0)
			(layer "B.Fab")
			(hide yes)
			(effects
				(font
					(size 1 1)
					(thickness 0.15)
				)
				(justify mirror)
			)
		)
		(property "Public" ""
			(at 378.56 286.36 0)
			(layer "B.Fab")
			(hide yes)
			(effects
				(font
					(size 1 1)
					(thickness 0.15)
				)
				(justify mirror)
			)
		)
		(property "Val" "10n"
			(at 378.56 286.36 0)
			(layer "B.Fab")
			(hide yes)
			(effects
				(font
					(size 1 1)
					(thickness 0.15)
				)
				(justify mirror)
			)
		)
		(property "Voltage" "50V"
			(at 378.56 286.36 0)
			(layer "B.Fab")
			(hide yes)
			(effects
				(font
					(size 1 1)
					(thickness 0.15)
				)
				(justify mirror)
			)
		)
		(sheetname "/FPGA Supply/")
		(sheetfile "fpga-supply.kicad_sch")
		(attr smd)
		(fp_rect
			(start -0.925 0.47)
			(end 0.925 -0.47)
			(stroke
				(width 0.05)
				(type default)
			)
			(fill no)
			(layer "B.CrtYd")
		)
		(fp_line
			(start 0.504 0.25)
			(end 0.504 -0.248)
			(stroke
				(width 0.15)
				(type solid)
			)
			(layer "B.Fab")
		)
		(fp_line
			(start 0.504 -0.248)
			(end -0.494 -0.248)
			(stroke
				(width 0.15)
				(type solid)
			)
			(layer "B.Fab")
		)
		(fp_line
			(start -0.494 0.25)
			(end 0.504 0.25)
			(stroke
				(width 0.15)
				(type solid)
			)
			(layer "B.Fab")
		)
		(fp_line
			(start -0.494 -0.248)
			(end -0.494 0.25)
			(stroke
				(width 0.15)
				(type solid)
			)
			(layer "B.Fab")
		)
		(fp_text user "Author: Antmicro"
			(at -0.939 -3.399 0)
			(layer "B.Fab")
			(effects
				(font
					(size 0.7 0.7)
					(thickness 0.15)
				)
				(justify left bottom mirror)
			)
		)
		(fp_text user "License: Apache-2.0"
			(at -0.939 -5.799 0)
			(layer "B.Fab")
			(effects
				(font
					(size 0.7 0.7)
					(thickness 0.15)
				)
				(justify left bottom mirror)
			)
		)
		(fp_text user "${REFERENCE}"
			(at -0.939 -4.599 0)
			(layer "B.Fab")
			(effects
				(font
					(size 0.7 0.7)
					(thickness 0.15)
				)
				(justify left bottom mirror)
			)
		)
		(pad "1" smd roundrect
			(at -0.48 0 180)
			(size 0.59 0.64)
			(layers "B.Cu" "B.Mask" "B.Paste")
			(roundrect_rratio 0.25)
			(net 417 "GND")
			(pintype "passive")
		)
		(pad "2" smd roundrect
			(at 0.48 0 180)
			(size 0.59 0.64)
			(layers "B.Cu" "B.Mask" "B.Paste")
			(roundrect_rratio 0.25)
			(net 47 "+1V05")
			(pintype "passive")
		)
	)
)
